# T6G (Grand Teton) — schematic netlist excerpt (pin names and nets, part order shuffled) for the footprints in the layout excerpt that follows; sources: Cadence DE-HDL packaged netlist, KiCad conversion of 04192023_DAF0TMB3IC0_F0TG_MB_C_brd_V02_OCP.brd

PQ10  MOSFET_PCH_GDS_ESD_PROTECTED  PJA3415AE IC  pkg SOT23_GDSXC  page 200
  D  = PVDDCR_CPU1_P0_EN1_ADDR_CFG
  G  = PVDDIO_P0_EN_G
  S  = P3V3_AUX

PQ16  MOSFET_N  BSS138K IC  pkg SMLF  page 217
  DRAIN  = PVDDIO_P1_EN_G
  GATE  = PVDDIO_P1_EN_R
  SOURCE  = GND

(kicad_pcb
	(version 20260206)
	(generator "pcbnew")
	(generator_version "10.0")
	(general
		(thickness 1.6)
		(legacy_teardrops no)
	)
	(paper "A4")
	(title_block
		(title "04192023_DAF0TMB3IC0_F0TG_MB_C_brd_V02_OCP.brd")
		(comment 1 "Grand Teton / footprints 3972-3973 of 8354")
	)
	(layers
		(0 "F.Cu" signal "TOP")
		(4 "In1.Cu" signal "GND")
		(6 "In2.Cu" signal "IN1")
		(8 "In3.Cu" signal "GND1")
		(10 "In4.Cu" signal "IN2")
		(12 "In5.Cu" signal "GND2")
		(14 "In6.Cu" signal "IN3")
		(16 "In7.Cu" signal "GND3")
		(18 "In8.Cu" signal "VCC")
		(20 "In9.Cu" signal "VCC1")
		(22 "In10.Cu" signal "GND4")
		(24 "In11.Cu" signal "IN4")
		(26 "In12.Cu" signal "GND5")
		(28 "In13.Cu" signal "IN5")
		(30 "In14.Cu" signal "GND6")
		(32 "In15.Cu" signal "IN6")
		(34 "In16.Cu" signal "GND7")
		(2 "B.Cu" signal "BOTTOM")
		(9 "F.Adhes" user "F.Adhesive")
		(11 "B.Adhes" user "B.Adhesive")
		(13 "F.Paste" user "Package Geometry/Pastemask Top")
		(15 "B.Paste" user "Package Geometry/Pastemask Bottom")
		(5 "F.SilkS" user "Ref Des/Silkscreen Top")
		(7 "B.SilkS" user "Ref Des/Silkscreen Bottom")
		(1 "F.Mask" user "Board Geometry/Soldermask Top")
		(3 "B.Mask" user "Board Geometry/Soldermask Bottom")
		(17 "Dwgs.User" user "User.Drawings")
		(19 "Cmts.User" user "User.Comments")
		(21 "Eco1.User" user "User.Eco1")
		(23 "Eco2.User" user "User.Eco2")
		(25 "Edge.Cuts" user "Board Geometry/Outline")
		(27 "Margin" user)
		(31 "F.CrtYd" user "Package Geometry/Place Bound Top")
		(29 "B.CrtYd" user "Package Geometry/Place Bound Bottom")
		(35 "F.Fab" user "Ref Des/Assembly Top")
		(33 "B.Fab" user "Ref Des/Assembly Bottom")
	)
	(footprint ""
		(layer "F.Cu")
		(at 295.6814 -367.03)
		(property "Reference" "PQ10"
			(at -1.458214 -3.378454 0)
			(unlocked yes)
			(layer "F.SilkS")
			(effects
				(font
					(size 0.7874 0.5842)
					(thickness 0.1524)
				)
				(justify left)
			)
		)
		(property "Value" ""
			(at 0 0 0)
			(layer "F.Fab")
			(effects
				(font
					(size 1.27 1.27)
				)
			)
		)
		(duplicate_pad_numbers_are_jumpers no)
		(fp_line
			(start -1.603248 -1.500124)
			(end 1.603248 -1.500124)
			(stroke
				(width 0.1524)
				(type default)
			)
			(layer "F.SilkS")
		)
		(fp_line
			(start -1.603248 1.500124)
			(end -1.603248 -1.500124)
			(stroke
				(width 0.1524)
				(type default)
			)
			(layer "F.SilkS")
		)
		(fp_line
			(start 1.603248 -1.500124)
			(end 1.603248 1.500124)
			(stroke
				(width 0.1524)
				(type default)
			)
			(layer "F.SilkS")
		)
		(fp_line
			(start 1.603248 1.500124)
			(end -1.603248 1.500124)
			(stroke
				(width 0.1524)
				(type default)
			)
			(layer "F.SilkS")
		)
		(fp_line
			(start -1.249934 -1.169924)
			(end -1.249934 -0.729996)
			(stroke
				(width 0.1)
				(type default)
			)
			(layer "F.Fab")
		)
		(fp_line
			(start -1.249934 -0.729996)
			(end -0.6985 -0.729996)
			(stroke
				(width 0.1)
				(type default)
			)
			(layer "F.Fab")
		)
		(fp_line
			(start -1.249934 0.729996)
			(end -1.249934 1.169924)
			(stroke
				(width 0.1)
				(type default)
			)
			(layer "F.Fab")
		)
		(fp_line
			(start -1.249934 1.169924)
			(end -0.700024 1.169924)
			(stroke
				(width 0.1)
				(type default)
			)
			(layer "F.Fab")
		)
		(fp_line
			(start -0.700024 -1.500124)
			(end -0.700024 -1.169924)
			(stroke
				(width 0.1)
				(type default)
			)
			(layer "F.Fab")
		)
		(fp_line
			(start -0.700024 -1.169924)
			(end -1.249934 -1.169924)
			(stroke
				(width 0.1)
				(type default)
			)
			(layer "F.Fab")
		)
		(fp_line
			(start -0.700024 1.169924)
			(end -0.700024 1.500124)
			(stroke
				(width 0.1)
				(type default)
			)
			(layer "F.Fab")
		)
		(fp_line
			(start -0.700024 1.500124)
			(end 0.700024 1.500124)
			(stroke
				(width 0.1)
				(type default)
			)
			(layer "F.Fab")
		)
		(fp_line
			(start -0.6985 -0.729996)
			(end -0.6985 0.729996)
			(stroke
				(width 0.1)
				(type default)
			)
			(layer "F.Fab")
		)
		(fp_line
			(start -0.6985 0.729996)
			(end -1.249934 0.729996)
			(stroke
				(width 0.1)
				(type default)
			)
			(layer "F.Fab")
		)
		(fp_line
			(start 0.700024 -1.500124)
			(end -0.700024 -1.500124)
			(stroke
				(width 0.1)
				(type default)
			)
			(layer "F.Fab")
		)
		(fp_line
			(start 0.700024 -0.219964)
			(end 0.700024 -1.500124)
			(stroke
				(width 0.1)
				(type default)
			)
			(layer "F.Fab")
		)
		(fp_line
			(start 0.700024 0.219964)
			(end 1.249934 0.219964)
			(stroke
				(width 0.1)
				(type default)
			)
			(layer "F.Fab")
		)
		(fp_line
			(start 0.700024 1.500124)
			(end 0.700024 0.219964)
			(stroke
				(width 0.1)
				(type default)
			)
			(layer "F.Fab")
		)
		(fp_line
			(start 1.249934 -0.219964)
			(end 0.700024 -0.219964)
			(stroke
				(width 0.1)
				(type default)
			)
			(layer "F.Fab")
		)
		(fp_line
			(start 1.249934 0.219964)
			(end 1.249934 -0.219964)
			(stroke
				(width 0.1)
				(type default)
			)
			(layer "F.Fab")
		)
		(fp_rect
			(start -0.700024 1.500124)
			(end 0.700024 -1.500124)
			(stroke
				(width 0)
				(type default)
			)
			(fill no)
			(layer "F.Fab")
		)
		(pad "D" smd rect
			(at 0.999998 0 270)
			(size 0.8128 0.9144)
			(layers "F.Cu" "F.Mask" "F.Paste")
			(net "PVDDCR_CPU1_P0_EN1_ADDR_CFG")
		)
		(pad "G" smd rect
			(at -0.999998 -0.94996 270)
			(size 0.8128 0.9144)
			(layers "F.Cu" "F.Mask" "F.Paste")
			(net "PVDDIO_P0_EN_G")
		)
		(pad "S" smd rect
			(at -0.999998 0.94996 270)
			(size 0.8128 0.9144)
			(layers "F.Cu" "F.Mask" "F.Paste")
			(net "P3V3_AUX")
		)
	)
	(footprint ""
		(layer "F.Cu")
		(at 19.304 -361.442 90)
		(property "Reference" "PQ16"
			(at -0.01905 -2.928874 90)
			(unlocked yes)
			(layer "F.SilkS")
			(effects
				(font
					(size 0.7874 0.5842)
					(thickness 0.1524)
				)
			)
		)
		(property "Value" ""
			(at 0 0 90)
			(layer "F.Fab")
			(effects
				(font
					(size 1.27 1.27)
				)
			)
		)
		(duplicate_pad_numbers_are_jumpers no)
		(fp_line
			(start -1.949958 -1.610106)
			(end 1.949958 -1.610106)
			(stroke
				(width 0.1524)
				(type default)
			)
			(layer "F.SilkS")
		)
		(fp_line
			(start 1.949958 -1.560068)
			(end 1.949958 1.610106)
			(stroke
				(width 0.1524)
				(type default)
			)
			(layer "F.SilkS")
		)
		(fp_line
			(start 1.949958 1.610106)
			(end -1.949958 1.610106)
			(stroke
				(width 0.1524)
				(type default)
			)
			(layer "F.SilkS")
		)
		(fp_line
			(start -1.949958 1.610106)
			(end -1.949958 -1.610106)
			(stroke
				(width 0.1524)
				(type default)
			)
			(layer "F.SilkS")
		)
		(fp_line
			(start 0.750062 -1.560068)
			(end 0.750062 1.560068)
			(stroke
				(width 0.1)
				(type default)
			)
			(layer "F.Fab")
		)
		(fp_line
			(start -0.750062 -1.560068)
			(end 0.750062 -1.560068)
			(stroke
				(width 0.1)
				(type default)
			)
			(layer "F.Fab")
		)
		(fp_line
			(start 0.750062 1.560068)
			(end -0.750062 1.560068)
			(stroke
				(width 0.1)
				(type default)
			)
			(layer "F.Fab")
		)
		(fp_line
			(start -0.750062 1.560068)
			(end -0.750062 -1.560068)
			(stroke
				(width 0.1)
				(type default)
			)
			(layer "F.Fab")
		)
		(pad "D" smd rect
			(at 1.100074 0)
			(size 1.016 1.4224)
			(layers "F.Cu" "F.Mask" "F.Paste")
			(net "PVDDIO_P1_EN_G")
		)
		(pad "G" smd rect
			(at -1.100074 -0.94996)
			(size 1.016 1.4224)
			(layers "F.Cu" "F.Mask" "F.Paste")
			(net "PVDDIO_P1_EN_R")
		)
		(pad "S" smd rect
			(at -1.100074 0.94996)
			(size 1.016 1.4224)
			(layers "F.Cu" "F.Mask" "F.Paste")
			(net "GND")
		)
	)
)
